(kicad_pcb
	(version 20260206)
	(generator "pcbnew")
	(generator_version "10.0")
	(general
		(thickness 1.6)
		(legacy_teardrops no)
	)
	(paper "A4")
	(title_block
		(title "Bryce Canyon_F.DPB_16315-1-OCP.brd")
		(comment 1 "Bryce Canyon / footprints 1121-1123 of 2223")
	)
	(layers
		(0 "F.Cu" signal "TOP")
		(4 "In1.Cu" signal "L2GND")
		(6 "In2.Cu" signal "L3")
		(8 "In3.Cu" signal "L4GND")
		(10 "In4.Cu" signal "L5")
		(12 "In5.Cu" signal "L6VCC")
		(14 "In6.Cu" signal "L7VCC")
		(16 "In7.Cu" signal "L8")
		(18 "In8.Cu" signal "L9GND")
		(20 "In9.Cu" signal "L10")
		(22 "In10.Cu" signal "L11GND")
		(2 "B.Cu" signal "BOTTOM")
		(9 "F.Adhes" user "F.Adhesive")
		(11 "B.Adhes" user "B.Adhesive")
		(13 "F.Paste" user "Package Geometry/Pastemask Top")
		(15 "B.Paste" user "Package Geometry/Pastemask Bottom")
		(5 "F.SilkS" user "Ref Des/Silkscreen Top")
		(7 "B.SilkS" user "Ref Des/Silkscreen Bottom")
		(1 "F.Mask" user "Board Geometry/Soldermask Top")
		(3 "B.Mask" user "Board Geometry/Soldermask Bottom")
		(17 "Dwgs.User" user "User.Drawings")
		(19 "Cmts.User" user "User.Comments")
		(21 "Eco1.User" user "User.Eco1")
		(23 "Eco2.User" user "User.Eco2")
		(25 "Edge.Cuts" user "Board Geometry/Outline")
		(27 "Margin" user)
		(31 "F.CrtYd" user "Package Geometry/Place Bound Top")
		(29 "B.CrtYd" user "Package Geometry/Place Bound Bottom")
		(35 "F.Fab" user "Ref Des/Assembly Top")
		(33 "B.Fab" user "Ref Des/Assembly Bottom")
	)
	(footprint ""
		(layer "F.Cu")
		(at 122.849894 -57.909968 -90)
		(property "Reference" "HDDSAS27"
			(at 0 0 270)
			(layer "F.SilkS")
			(hide yes)
			(effects
				(font
					(size 1.27 1.27)
				)
			)
		)
		(property "Value" "SKT-SAS15P-14P-45-GP"
			(at -20.7645 -8.9789 270)
			(unlocked yes)
			(layer "F.Fab")
			(hide yes)
			(effects
				(font
					(size 1.016 1.016)
					(thickness 0.1524)
				)
			)
		)
		(property "Device Type" "10120818-001C-TRLF"
			(at -20.7645 -10.5029 270)
			(unlocked yes)
			(layer "F.Fab")
			(hide yes)
			(effects
				(font
					(size 1.016 1.016)
					(thickness 0.1524)
				)
			)
		)
		(duplicate_pad_numbers_are_jumpers no)
		(fp_line
			(start 1.651 4.2926)
			(end 1.651 3.0099)
			(stroke
				(width 0.1524)
				(type default)
			)
			(layer "F.SilkS")
		)
		(fp_line
			(start 8.509 4.2926)
			(end 1.651 4.2926)
			(stroke
				(width 0.1524)
				(type default)
			)
			(layer "F.SilkS")
		)
		(fp_line
			(start -23.4188 3.0099)
			(end -23.4188 -3.2512)
			(stroke
				(width 0.1524)
				(type default)
			)
			(layer "F.SilkS")
		)
		(fp_line
			(start 1.651 3.0099)
			(end -23.4188 3.0099)
			(stroke
				(width 0.1524)
				(type default)
			)
			(layer "F.SilkS")
		)
		(fp_line
			(start 8.509 3.0099)
			(end 8.509 4.2926)
			(stroke
				(width 0.1524)
				(type default)
			)
			(layer "F.SilkS")
		)
		(fp_line
			(start 23.4188 3.0099)
			(end 8.509 3.0099)
			(stroke
				(width 0.1524)
				(type default)
			)
			(layer "F.SilkS")
		)
		(fp_line
			(start -23.4188 -3.2512)
			(end 23.4188 -3.2512)
			(stroke
				(width 0.1524)
				(type default)
			)
			(layer "F.SilkS")
		)
		(fp_line
			(start 23.4188 -3.2512)
			(end 23.4188 3.0099)
			(stroke
				(width 0.1524)
				(type default)
			)
			(layer "F.SilkS")
		)
		(fp_line
			(start 15.5067 -3.3401)
			(end 16.2687 -3.3401)
			(stroke
				(width 0.3302)
				(type default)
			)
			(layer "F.SilkS")
		)
		(fp_poly
			(pts
				(xy 15.868904 -3.230372) (xy 16.503904 -3.865372) (xy 15.233904 -3.865372)
			)
			(stroke
				(width 0)
				(type default)
			)
			(fill yes)
			(layer "F.SilkS")
		)
		(fp_poly
			(pts
				(xy -22.8727 -2.7559) (xy 22.8727 -2.7559) (xy 22.8727 2.7559) (xy 8.255 2.7559) (xy 8.255 3.5179)
				(xy 1.905 3.5179) (xy 1.905 2.7559) (xy -22.8727 2.7559)
			)
			(stroke
				(width 0)
				(type default)
			)
			(fill no)
			(layer "F.CrtYd")
		)
		(fp_poly
			(pts
				(xy 1.397 4.5466) (xy 1.397 3.2639) (xy -23.6728 3.2639) (xy -23.6728 -3.5052) (xy 23.6728 -3.5052)
				(xy 23.6728 -0.00635) (xy 22.8727 -0.00635) (xy 22.8727 -2.7559) (xy -22.8727 -2.7559) (xy -22.8727 2.7559)
				(xy 1.905 2.7559) (xy 1.905 3.5179) (xy 8.255 3.5179) (xy 8.255 2.7559) (xy 22.8727 2.7559) (xy 22.8727 0.00635)
				(xy 23.6728 0.00635) (xy 23.6728 3.2639) (xy 8.763 3.2639) (xy 8.763 4.5466)
			)
			(stroke
				(width 0)
				(type default)
			)
			(fill no)
			(layer "F.CrtYd")
		)
		(fp_poly
			(pts
				(xy 1.397 4.5466) (xy 1.397 3.2639) (xy -23.6728 3.2639) (xy -23.6728 -3.5052) (xy 23.6728 -3.5052)
				(xy 23.6728 3.2639) (xy 8.763 3.2639) (xy 8.763 4.5466)
			)
			(stroke
				(width 0)
				(type default)
			)
			(fill no)
			(layer "F.Fab")
		)
		(pad "" np_thru_hole circle
			(at -18.874994 0 270)
			(size 0.254 0.254)
			(drill 1.3462)
			(layers "*.Cu" "*.Mask")
			(clearance 0.9017)
			(thermal_gap 0.9017)
		)
		(pad "" np_thru_hole circle
			(at 18.874994 0 270)
			(size 0.254 0.254)
			(drill 0.9398)
			(layers "*.Cu" "*.Mask")
			(clearance 0.6985)
			(thermal_gap 0.6985)
		)
		(pad "G1" smd rect
			(at 21.874988 0 270)
			(size 2.5908 2.5908)
			(layers "F.Cu" "F.Mask" "F.Paste")
			(net "GND")
		)
		(pad "G2" smd rect
			(at -21.874988 0 270)
			(size 2.5908 2.5908)
			(layers "F.Cu" "F.Mask" "F.Paste")
			(net "GND")
		)
		(pad "P1" smd rect
			(at 1.905 -1.82499 270)
			(size 0.6096 2.3622)
			(layers "F.Cu" "F.Mask" "F.Paste")
			(net "Net_2076")
		)
		(pad "P2" smd rect
			(at 0.635 -1.82499 270)
			(size 0.6096 2.3622)
			(layers "F.Cu" "F.Mask" "F.Paste")
			(net "Net_2077")
		)
		(pad "P3" smd rect
			(at -0.635 -1.82499 270)
			(size 0.6096 2.3622)
			(layers "F.Cu" "F.Mask" "F.Paste")
			(net "Net_2078")
		)
		(pad "P4" smd rect
			(at -1.905 -1.82499 270)
			(size 0.6096 2.3622)
			(layers "F.Cu" "F.Mask" "F.Paste")
			(net "GND")
		)
		(pad "P5" smd rect
			(at -3.175 -1.82499 270)
			(size 0.6096 2.3622)
			(layers "F.Cu" "F.Mask" "F.Paste")
			(net "HDD_PRSNT_27")
		)
		(pad "P6" smd rect
			(at -4.445 -1.82499 270)
			(size 0.6096 2.3622)
			(layers "F.Cu" "F.Mask" "F.Paste")
			(net "GND")
		)
		(pad "P7" smd rect
			(at -5.715 -1.82499 270)
			(size 0.6096 2.3622)
			(layers "F.Cu" "F.Mask" "F.Paste")
			(net "5V_PRE_27")
		)
		(pad "P8" smd rect
			(at -6.985 -1.82499 270)
			(size 0.6096 2.3622)
			(layers "F.Cu" "F.Mask" "F.Paste")
			(net "P5V_HDD27")
		)
		(pad "P9" smd rect
			(at -8.255 -1.82499 270)
			(size 0.6096 2.3622)
			(layers "F.Cu" "F.Mask" "F.Paste")
			(net "P5V_HDD27")
		)
		(pad "P10" smd rect
			(at -9.525 -1.82499 270)
			(size 0.6096 2.3622)
			(layers "F.Cu" "F.Mask" "F.Paste")
			(net "GND")
		)
		(pad "P11" smd rect
			(at -10.795 -1.82499 270)
			(size 0.6096 2.3622)
			(layers "F.Cu" "F.Mask" "F.Paste")
			(net "ACT_HDD_27")
		)
		(pad "P12" smd rect
			(at -12.065 -1.82499 270)
			(size 0.6096 2.3622)
			(layers "F.Cu" "F.Mask" "F.Paste")
			(net "GND")
		)
		(pad "P13" smd rect
			(at -13.335 -1.82499 270)
			(size 0.6096 2.3622)
			(layers "F.Cu" "F.Mask" "F.Paste")
			(net "12V_PRE_27")
		)
		(pad "P14" smd rect
			(at -14.605 -1.82499 270)
			(size 0.6096 2.3622)
			(layers "F.Cu" "F.Mask" "F.Paste")
			(net "P12V_HDD27")
		)
		(pad "P15" smd rect
			(at -15.875 -1.82499 270)
			(size 0.6096 2.3622)
			(layers "F.Cu" "F.Mask" "F.Paste")
			(net "P12V_HDD27")
		)
		(pad "S1" smd rect
			(at 15.875 -1.82499 270)
			(size 0.6096 2.3622)
			(layers "F.Cu" "F.Mask" "F.Paste")
			(net "GND")
		)
		(pad "S2" smd rect
			(at 14.605 -1.82499 270)
			(size 0.6096 2.3622)
			(layers "F.Cu" "F.Mask" "F.Paste")
			(net "SAS_HDD_RX_P27")
		)
		(pad "S3" smd rect
			(at 13.335 -1.82499 270)
			(size 0.6096 2.3622)
			(layers "F.Cu" "F.Mask" "F.Paste")
			(net "SAS_HDD_RX_N27")
		)
		(pad "S4" smd rect
			(at 12.065 -1.82499 270)
			(size 0.6096 2.3622)
			(layers "F.Cu" "F.Mask" "F.Paste")
			(net "GND")
		)
		(pad "S5" smd rect
			(at 10.795 -1.82499 270)
			(size 0.6096 2.3622)
			(layers "F.Cu" "F.Mask" "F.Paste")
			(net "PHY_DRV_A_TO_SCC_A_27_DN")
		)
		(pad "S6" smd rect
			(at 9.525 -1.82499 270)
			(size 0.6096 2.3622)
			(layers "F.Cu" "F.Mask" "F.Paste")
			(net "PHY_DRV_A_TO_SCC_A_27_DP")
		)
		(pad "S7" smd rect
			(at 8.255 -1.82499 270)
			(size 0.6096 2.3622)
			(layers "F.Cu" "F.Mask" "F.Paste")
			(net "GND")
		)
		(pad "S8" smd rect
			(at 7.480046 2.845054 270)
			(size 0.508 2.3622)
			(layers "F.Cu" "F.Mask" "F.Paste")
			(net "GND")
		)
		(pad "S9" smd rect
			(at 6.679946 2.845054 270)
			(size 0.508 2.3622)
			(layers "F.Cu" "F.Mask" "F.Paste")
			(net "Net_465")
		)
		(pad "S10" smd rect
			(at 5.8801 2.845054 270)
			(size 0.508 2.3622)
			(layers "F.Cu" "F.Mask" "F.Paste")
			(net "Net_357")
		)
		(pad "S11" smd rect
			(at 5.08 2.845054 270)
			(size 0.508 2.3622)
			(layers "F.Cu" "F.Mask" "F.Paste")
			(net "GND")
		)
		(pad "S12" smd rect
			(at 4.2799 2.845054 270)
			(size 0.508 2.3622)
			(layers "F.Cu" "F.Mask" "F.Paste")
			(net "Net_393")
		)
		(pad "S13" smd rect
			(at 3.480054 2.845054 270)
			(size 0.508 2.3622)
			(layers "F.Cu" "F.Mask" "F.Paste")
			(net "Net_429")
		)
		(pad "S14" smd rect
			(at 2.679954 2.845054 270)
			(size 0.508 2.3622)
			(layers "F.Cu" "F.Mask" "F.Paste")
			(net "GND")
		)
		(zone
			(layer "F.Cu")
			(hatch none 0.5)
			(connect_pads
				(clearance 0)
			)
			(min_thickness 0.25)
			(keepout
				(tracks not_allowed)
				(vias allowed)
				(pads allowed)
				(copperpour not_allowed)
				(footprints allowed)
			)
			(placement
				(enabled no)
				(sheetname "")
			)
			(fill
				(thermal_gap 0.5)
				(thermal_bridge_width 0.5)
				(island_removal_mode 0)
			)
			(polygon
				(pts
					(xy 126.507494 -74.648568) (xy 119.433594 -74.648568) (xy 119.433594 -81.582768) (xy 120.538494 -81.582768)
					(xy 120.538494 -77.467968) (xy 125.161294 -77.467968) (xy 125.161294 -81.582768) (xy 126.507494 -81.582768)
				)
			)
		)
		(zone
			(layer "F.Cu")
			(hatch none 0.5)
			(connect_pads
				(clearance 0)
			)
			(min_thickness 0.25)
			(keepout
				(tracks allowed)
				(vias not_allowed)
				(pads allowed)
				(copperpour not_allowed)
				(footprints allowed)
			)
			(placement
				(enabled no)
				(sheetname "")
			)
			(fill
				(thermal_gap 0.5)
				(thermal_bridge_width 0.5)
				(island_removal_mode 0)
			)
			(polygon
				(pts
					(xy 126.507494 -74.648568) (xy 119.433594 -74.648568) (xy 119.433594 -81.582768) (xy 120.538494 -81.582768)
					(xy 120.538494 -77.467968) (xy 125.161294 -77.467968) (xy 125.161294 -81.582768) (xy 126.507494 -81.582768)
				)
			)
		)
		(zone
			(layer "F.Cu")
			(hatch none 0.5)
			(connect_pads
				(clearance 0)
			)
			(min_thickness 0.25)
			(keepout
				(tracks not_allowed)
				(vias allowed)
				(pads allowed)
				(copperpour not_allowed)
				(footprints allowed)
			)
			(placement
				(enabled no)
				(sheetname "")
			)
			(fill
				(thermal_gap 0.5)
				(thermal_bridge_width 0.5)
				(island_removal_mode 0)
			)
			(polygon
				(pts
					(xy 126.507494 -41.171368) (xy 119.433594 -41.171368) (xy 119.433594 -34.237168) (xy 120.538494 -34.237168)
					(xy 120.538494 -38.351968) (xy 125.161294 -38.351968) (xy 125.161294 -34.237168) (xy 126.507494 -34.237168)
				)
			)
		)
		(zone
			(layer "F.Cu")
			(hatch none 0.5)
			(connect_pads
				(clearance 0)
			)
			(min_thickness 0.25)
			(keepout
				(tracks allowed)
				(vias not_allowed)
				(pads allowed)
				(copperpour not_allowed)
				(footprints allowed)
			)
			(placement
				(enabled no)
				(sheetname "")
			)
			(fill
				(thermal_gap 0.5)
				(thermal_bridge_width 0.5)
				(island_removal_mode 0)
			)
			(polygon
				(pts
					(xy 126.507494 -41.171368) (xy 119.433594 -41.171368) (xy 119.433594 -34.237168) (xy 120.538494 -34.237168)
					(xy 120.538494 -38.351968) (xy 125.161294 -38.351968) (xy 125.161294 -34.237168) (xy 126.507494 -34.237168)
				)
			)
		)
		(zone
			(layers "F.Cu" "B.Cu" "In1.Cu" "In2.Cu" "In3.Cu" "In4.Cu" "In5.Cu" "In6.Cu"
				"In7.Cu" "In8.Cu" "In9.Cu" "In10.Cu"
			)
			(hatch none 0.5)
			(connect_pads
				(clearance 0)
			)
			(min_thickness 0.25)
			(keepout
				(tracks not_allowed)
				(vias allowed)
				(pads allowed)
				(copperpour not_allowed)
				(footprints allowed)
			)
			(placement
				(enabled no)
				(sheetname "")
			)
			(fill
				(thermal_gap 0.5)
				(thermal_bridge_width 0.5)
				(island_removal_mode 0)
			)
			(polygon
				(pts
					(arc
						(start 123.624594 -39.034974)
						(mid 122.075194 -39.034974)
						(end 123.624594 -39.034974)
					)
				)
			)
		)
		(zone
			(layers "F.Cu" "B.Cu" "In1.Cu" "In2.Cu" "In3.Cu" "In4.Cu" "In5.Cu" "In6.Cu"
				"In7.Cu" "In8.Cu" "In9.Cu" "In10.Cu"
			)
			(hatch none 0.5)
			(connect_pads
				(clearance 0)
			)
			(min_thickness 0.25)
			(keepout
				(tracks not_allowed)
				(vias allowed)
				(pads allowed)
				(copperpour not_allowed)
				(footprints allowed)
			)
			(placement
				(enabled no)
				(sheetname "")
			)
			(fill
				(thermal_gap 0.5)
				(thermal_bridge_width 0.5)
				(island_removal_mode 0)
			)
			(polygon
				(pts
					(arc
						(start 123.827794 -76.784962)
						(mid 121.871994 -76.784962)
						(end 123.827794 -76.784962)
					)
				)
			)
		)
	)
	(footprint ""
		(layer "F.Cu")
		(at 366.994948 -149.428454 90)
		(property "Reference" "R144"
			(at 0 0 90)
			(layer "F.SilkS")
			(hide yes)
			(effects
				(font
					(size 1.27 1.27)
				)
			)
		)
		(property "Value" "0R5J-5-GP"
			(at 0 -8.9535 90)
			(unlocked yes)
			(layer "F.Fab")
			(hide yes)
			(effects
				(font
					(size 1.27 1.016)
					(thickness 0.1524)
				)
			)
		)
		(property "Device Type" "R805H24"
			(at 0 -10.6299 90)
			(unlocked yes)
			(layer "F.Fab")
			(hide yes)
			(effects
				(font
					(size 1.27 1.016)
					(thickness 0.1524)
				)
			)
		)
		(duplicate_pad_numbers_are_jumpers no)
		(fp_line
			(start 0.889 -1.7018)
			(end -0.889 -1.7018)
			(stroke
				(width 0.1524)
				(type default)
			)
			(layer "F.SilkS")
		)
		(fp_line
			(start 0.889 -1.7018)
			(end 0.889 -0.381)
			(stroke
				(width 0.1524)
				(type default)
			)
			(layer "F.SilkS")
		)
		(fp_line
			(start -0.889 -1.7018)
			(end -0.889 0.2794)
			(stroke
				(width 0.1524)
				(type default)
			)
			(layer "F.SilkS")
		)
		(fp_line
			(start -0.889 0.0762)
			(end -0.889 1.7018)
			(stroke
				(width 0.1524)
				(type default)
			)
			(layer "F.SilkS")
		)
		(fp_line
			(start 0.889 1.7018)
			(end 0.889 -0.508)
			(stroke
				(width 0.1524)
				(type default)
			)
			(layer "F.SilkS")
		)
		(fp_line
			(start -0.889 1.7018)
			(end 0.889 1.7018)
			(stroke
				(width 0.1524)
				(type default)
			)
			(layer "F.SilkS")
		)
		(fp_poly
			(pts
				(xy 0.9652 -1.778) (xy 0.9652 1.778) (xy -0.9652 1.778) (xy -0.9652 -1.778)
			)
			(stroke
				(width 0)
				(type default)
			)
			(fill no)
			(layer "F.CrtYd")
		)
		(fp_rect
			(start -0.9652 1.778)
			(end 0.9652 -1.778)
			(stroke
				(width 0)
				(type default)
			)
			(fill no)
			(layer "F.Fab")
		)
		(pad "1" smd rect
			(at 0 -0.9652 90)
			(size 1.397 1.143)
			(layers "F.Cu" "F.Mask" "F.Paste")
			(net "MB1_CM_GATE_R")
		)
		(pad "2" smd rect
			(at 0 0.9652 90)
			(size 1.397 1.143)
			(layers "F.Cu" "F.Mask" "F.Paste")
			(net "MB1_CM_GATE_C")
		)
	)
	(footprint ""
		(layer "F.Cu")
		(at 370.144294 -149.417024 90)
		(property "Reference" "C568"
			(at 0 0 90)
			(layer "F.SilkS")
			(hide yes)
			(effects
				(font
					(size 1.27 1.27)
				)
			)
		)
		(property "Value" "SCD033U50V3KX-1GP"
			(at 0 -2.8194 90)
			(unlocked yes)
			(layer "F.Fab")
			(hide yes)
			(effects
				(font
					(size 1.016 1.016)
					(thickness 0.1524)
				)
			)
		)
		(property "Device Type" "C603H36"
			(at 0 -4.3434 90)
			(unlocked yes)
			(layer "F.Fab")
			(hide yes)
			(effects
				(font
					(size 1.016 1.016)
					(thickness 0.1524)
				)
			)
		)
		(duplicate_pad_numbers_are_jumpers no)
		(fp_line
			(start 0.508 0)
			(end -0.508 0)
			(stroke
				(width 0.2032)
				(type default)
			)
			(layer "F.SilkS")
		)
		(fp_rect
			(start -0.5842 1.3335)
			(end 0.5842 -1.3335)
			(stroke
				(width 0)
				(type default)
			)
			(fill no)
			(layer "F.CrtYd")
		)
		(fp_rect
			(start -0.5842 1.3335)
			(end 0.5842 -1.3335)
			(stroke
				(width 0)
				(type default)
			)
			(fill no)
			(layer "F.Fab")
		)
		(pad "1" smd custom
			(at 0 -0.762 90)
			(size 0.2159 0.2159)
			(layers "F.Cu" "F.Mask" "F.Paste")
			(net "MB1_CM_GATE_C")
			(options
				(clearance outline)
				(anchor circle)
			)
			(primitives
				(gr_poly
					(pts
						(arc
							(start -0.3302 -0.4318)
							(mid -0.402042 -0.402042)
							(end -0.4318 -0.3302)
						)
						(arc
							(start -0.4318 0.3302)
							(mid -0.402042 0.402042)
							(end -0.3302 0.4318)
						)
						(arc
							(start 0.3302 0.4318)
							(mid 0.402042 0.402042)
							(end 0.4318 0.3302)
						)
						(arc
							(start 0.4318 -0.3302)
							(mid 0.402042 -0.402042)
							(end 0.3302 -0.4318)
						)
					)
					(width 0)
					(fill yes)
				)
			)
		)
		(pad "2" smd custom
			(at 0 0.762 90)
			(size 0.2159 0.2159)
			(layers "F.Cu" "F.Mask" "F.Paste")
			(net "GND")
			(options
				(clearance outline)
				(anchor circle)
			)
			(primitives
				(gr_poly
					(pts
						(arc
							(start -0.3302 -0.4318)
							(mid -0.402042 -0.402042)
							(end -0.4318 -0.3302)
						)
						(arc
							(start -0.4318 0.3302)
							(mid -0.402042 0.402042)
							(end -0.3302 0.4318)
						)
						(arc
							(start 0.3302 0.4318)
							(mid 0.402042 0.402042)
							(end 0.4318 0.3302)
						)
						(arc
							(start 0.4318 -0.3302)
							(mid 0.402042 -0.402042)
							(end 0.3302 -0.4318)
						)
					)
					(width 0)
					(fill yes)
				)
			)
		)
	)
)
